# SCM (Grand Teton) — schematic netlist excerpt (pin names and nets, part order shuffled) for the footprints in the layout excerpt that follows; sources: Cadence DE-HDL packaged netlist, KiCad conversion of 12092022_DA0F0TMDCD0_F0T_Management_Board_D_brd_V3_OCP.brd

U25  LCMXO3LF2100C5BG256C  LCMXO3LF-2100C-5BG256C IC  pkg BGA256_0-8_14X14  page 34
  VCC_A1  = PVCCA_AUX_PLD
  NC1  = NC
  PT11C  = BSM_PRSNT_R1_N
  PT10A  = RST_PLTRST_R1_N
  PT11A  = RST_RSMRST_N
  \pt12d||tdi\  = JTAG_SCM_PLD_TDI
  \pt16c||tck\  = JTAG_SCM_PLD_TCK
  \pt17b||pclkc0_1\  = IRQ_BMC_PCH_NMI_R_N
  \pt18c||scl||pclkt0_0\  = SMB_BMC_MM16_R3_SCL
  PT19B  = NC
  PT21A  = RST_EXTRST_R_N
  PT22B  = FM_ADR_COMPLETE
  \pt24c||initn\  = PU_FPGA_NSTATUS
  PT22D  = SGPIO_CLK_PLD_0
  PT24B  = FM_THERMTRIP_DLY_LVC1_R_N
  VCC_A16  = PVCCA_AUX_PLD
  PL1C  = NC
  GND_B2  = GND
  PT9C  = IRQ_BMC_CPU_NMI_R
  PT11D  = RST_PCA9548_SENSOR_N
  PT9B  = FM_TPM_PRSNT_1_R_N
  PT11B  = FM_JTAG_BMC_MUX_SEL_R2
  PT13A  = IRQ_UV_DETECT_N
  \pt16d||tms\  = JTAG_SCM_PLD_TMS
  PT19A  = IRQ_PCH_SCI_WHEA_N
  \pt20d||programn\  = PU_PT20D
  PT22A  = IRQ_OC_DETECT_N
  PT23B  = SGPIO_PLD_LD_0
  PT22C  = IRQ_OC_DETECT_EN_N
  PT24A  = SGPIO_PLD_DI_0
  GND_B15  = GND
  PR1D  = FM_PECI_SEL_N
  PL2C  = NC
  PL1D  = NC
  GND_C3  = GND
  PT9A  = FM_TPM_PRSNT_0_R_N
  PT10B  = PWRGD_PSU_AC_PWROK_PLD
  \pt12c||tdo\  = JTAG_SCM_PLD_TDO
  PT13B  = RST_BMC_RSTBTN_OUT_N
  \pt17a||pclkt0_1\  = CLK_25M_OSC_FPGA
  \pt18d||sda||pclkc0_0\  = SMB_BMC_MM16_R3_SDA
  \pt20c||jtagenb\  = JTAG_SCM_PLD_R_JTAGEN
  PT21B  = PWRGD_CPUPWRGD_LVC1
  PT23A  = SGPIO_PLD_DO_0
  \pt24d||done\  = PU_FPGA_CONFIG_DONE
  GND_C14  = GND
  PR1C  = VOL_SEN_ALERT_R
  PR2C  = SMB_BMC_ALERT3_R1_N
  \pl1b||l_gpllc_fb\  = NC
  PL2D  = NC
  \pl1a||l_gpllt_fb\  = NC
  GND_D4  = GND
  VCCIO0_D5  = VCCIO0
  PT12A  = FM_BMC_DBP_PRESENT_N
  PT13D  = FM_ME_BT_DONE
  PT17C  = FM_PCH_BMC_THERMTRIP_N
  PT18B  = NC
  PT20A  = NC
  PT21D  = IRQ_CPU1_VRHOT_N
  VCCIO0_D12  = VCCIO0
  GND_D13  = GND
  PR1A  = H_CPU0_MEMTRIP_LVC1_N
  PR2D  = SMB_BMC_ALERT4_R1_N
  PR2A  = H_CPU1_MEMTRIP_LVC1_N
  \pl3a||pclkt5_0\  = NC
  \pl2a||l_gpllt_in\  = NC
  \pl2b||l_gpllc_in\  = NC
  VCCIO5  = VCCIO5
  GND_E5  = GND
  PT13C  = BMC_CPLD_GPIO_2_R2
  PT12B  = PWRGD_PCH_PWROK
  PT16B  = FM_BIOS_POST_CMPLT_BMC_N
  PT17D  = H_CPU1_PROCHOT_LVC1_R_N
  PT20B  = FM_CPU_MSMI_CATERR_LVT3_PLD_N
  PT19D  = TP_PLD_19D
  GND_E12  = GND
  VCCIO1_E13  = VCCIO1
  PR2B  = IRQ_SGPIO_R_N
  PR1B  = FM_SPD_REMOTE_EN_R
  PR3A  = RST_SGPIO_RESET_R_N
  PL4B  = NC
  \pl3b||pclkc5_0\  = NC
  PL4A  = NC
  PL3C  = NC
  PL5C  = NC
  GND_F6  = GND
  PT16A  = FM_PCIE_M2_SSD0_PRSNT_N
  PT18A  = RST_SRST_PLD_BMC_R2_N
  PT19C  = NC
  PT21C  = IRQ_CPU0_VRHOT_N
  GND_F11  = GND
  PR4C  = TP_PLD_L3
  PR3C  = SMB_BMC_ALERT9_R1_N
  PR4A  = BMC_CPLD_GPIO_8_R2
  PR3B  = BMC_CPLD_GPIO_7_R2
  PR4B  = NC
  PL6A  = NC
  PL5A  = NC
  PL5B  = NC
  PL4D  = NC
  PL4C  = NC
  PL3D  = NC
  VCC_G7  = PVCCA_AUX_PLD
  VCCIO0_G8  = VCCIO0
  VCCIO0_G9  = VCCIO0
  VCC_G10  = PVCCA_AUX_PLD
  PR5C  = FM_SLPS3_GF_R_N
  PR3D  = SMB_BMC_ALERT10_R1_N
  PR4D  = RST_BMC_SELF_HW_R2
  PR5B  = NC
  PR5A  = NC
  PR6A  = BMC_CPLD_GPIO_12_R2
  PL7B  = NC
  PL6B  = NC
  PL7A  = NC
  PL6C  = NC
  PL9C  = NC
  PL5D  = NC
  VCCIO4_H7  = VCCIO4
  GND_H8  = GND
  GND_H9  = GND
  VCCIO1_H10  = VCCIO1
  PR9C  = RST_MB_STBY_R_N
  PR5D  = RST_ROT_CPU_R_N
  PR6C  = FM_ESPI_PLD_R_EN
  \pr7a||pclkt1_0\  = NC
  PR6B  = BMC_CPLD_GPIO_13_R2
  \pr7b||pclkc1_0\  = NC
  \pl7c||pclkt4_0\  = NC
  PL9A  = NC
  \pl7d||pclkc4_0\  = NC
  PL9D  = NC
  PL10C  = NC
  PL6D  = NC
  VCCIO4_J7  = VCCIO4
  GND_J8  = GND
  GND_J9  = GND
  VCCIO1_J10  = VCCIO1
  PR10C  = NC
  PR6D  = FM_THROTTLE_R_N
  PR9D  = FM_ADR_TRIGGER_N
  PR7D  = H_CPU0_PROCHOT_LVC1_R_N
  PR9A  = RST_BMC_HW_R
  PR7C  = FM_PMBUS_ALERT_EN
  PL9B  = NC
  PL10B  = NC
  PL10A  = NC
  PL11C  = NC
  PL12C  = NC
  PL10D  = NC
  VCC_K7  = PVCCA_AUX_PLD
  VCCIO2_K8  = VCCIO2
  VCCIO2_K9  = VCCIO2
  VCC_K10  = PVCCA_AUX_PLD
  PR12C  = FM_PCHHOT_R_N
  PR11D  = FM_BIOS_DEBUG_EN_N
  PR11C  = FM_BMC_READY_PLD_N
  PR10A  = FM_PWR_R_BTN
  PR10B  = PWRGD_SYS_PWROK_PLD
  PR9B  = NC
  PL11A  = NC
  \pl12a||pclkt3_0\  = NC
  PL11B  = NC
  PL12D  = NC
  PL11D  = NC
  GND_L6  = GND
  PB8D  = NC_FM_PFR_NO_SERVICE_ACT_N
  PB11D  = FM_PFR_DSW_PWROK_N
  PB12D  = FM_BMC_CPU_FBRK_OUT_R_N
  PB18D  = FM_UARTSW_MSB_R_N
  GND_L11  = GND
  PR10D  = FM_BMC_EN_DET_R
  PR12D  = FM_BMC_ONCTL_R_N
  PR11B  = SMB_BMC_ALERT12_N
  PR12A  = NC
  PR11A  = USB_OC0_REAR_R_N
  \pl12b||pclkc3_0\  = NC
  PL14A  = NC
  PL13A  = NC
  VCCIO3  = VCCIO3
  GND_M5  = GND
  PB11C  = BMC_MONITER
  PB9C  = CLK_GEN2_BMC_RC_OE_N
  PB16C  = PWRGD_P1V8_AUX_R1
  PB18C  = FM_UARTSW_LSB_R_N
  PB21C  = PU_FPGA_NCONFIG
  PB19D  = NC
  GND_M12  = GND
  VCCIO1_M13  = VCCIO1
  PR13A  = PWR_LED_CPLD
  PR13B  = PWRGD_P5V_AUX_R1
  PR12B  = NC
  PL13B  = NC
  PL13C  = NC
  PL14B  = NC
  GND_N4  = GND
  VCCIO2_N5  = VCCIO2
  PB8C  = FM_BMC_DEBUG_SW_R2_N
  PB9D  = IRQ_SML0_ALERT_R_N
  PB12C  = CLK_BUF1_GPU_FPGA_OE_R_N
  PB16D  = PWRGD_P3V3_RGM_R1
  PB19C  = NC
  PB21D  = NC
  VCCIO2_N12  = VCCIO2
  GND_N13  = GND
  PR14B  = PWRGD_P2V5_AUX_R1
  PR13C  = AC_PWR_BTN_R2_N
  PR14A  = PWRGD_P3V3_AUX_R1
  PL13D  = NC
  PL14D  = NC
  GND_P3  = GND
  PB3A  = FM_P12V_HSC_ENABLE_R2
  PB5B  = TP_PLD_C13
  \pb8a||mclk||cclk\  = FM_HDD_LED_N
  PB9B  = GPU_WP_HW_CTRL_R_N
  PB12A  = GPU_FPGA_RST_N
  \pb16b||pclkc2_1\  = PWRGD_P1V0_AUX_R1
  PB19A  = NC
  PB21B  = NC
  PB24A  = NC
  \pb25b||si||sispi\  = NC
  GND_P14  = GND
  PR14C  = NC
  PR13D  = NC
  PL14C  = NC
  GND_R2  = GND
  PB3D  = PWRGD_DSW_PWROK_R2
  PB6D  = FM_BMC_SUSACK_R2_N
  \pb5a||csspin\  = FM_DEBUG_PORT_R2_PRSNT_N
  PB6B  = FM_BMC_CRASHLOG_TRIG_R2_N
  PB9A  = GPU_NVS_PWR_BRAKE_R_N
  \pb11b||pclkc2_0\  = NC_FM_PFR_UPDATE_N
  PB18A  = NC
  PB19B  = NC
  PB22A  = NC
  \pb25a||sn\  = PU_PB25A
  PB22C  = NC
  PB25D  = SMB_BMC_MM16_R4_SDA
  GND_R15  = GND
  PR14D  = SMB_BMC_ALERT16_R2_N
  VCC_T1  = PVCCA_AUX_PLD
  PB3C  = FM_SOL_UART_CH_SEL_R2
  PB6C  = RST_WDTRST_PLD_R2_N
  PB3B  = NC
  PB6A  = IRQ_PCH_TPM_SPI_R2_N
  \pb8b||so||spiso\  = FM_PCH_BEEP_LED
  \pb11a||pclkt2_0\  = RST_PFR_OVR_RTC_R
  PB12B  = FM_JTAG_TCK_MUX_BMC_SEL
  \pb16a||pclkt2_1\  = PWRGD_P1V2_AUX_R1
  PB18B  = NC
  PB21A  = NC
  PB22B  = NC
  PB24B  = NC
  PB22D  = NC
  PB25C  = SMB_BMC_MM16_R4_SCL
  VCC_T16  = PVCCA_AUX_PLD

(kicad_pcb
	(version 20260206)
	(generator "pcbnew")
	(generator_version "10.0")
	(general
		(thickness 1.6)
		(legacy_teardrops no)
	)
	(paper "A4")
	(title_block
		(title "12092022_DA0F0TMDCD0_F0T_Management_Board_D_brd_V3_OCP.brd")
		(comment 1 "Grand Teton / footprint 162 of 1440 (U25), pads 93-140 of 256")
	)
	(layers
		(0 "F.Cu" signal "TOP")
		(4 "In1.Cu" signal "GND")
		(6 "In2.Cu" signal "IN1")
		(8 "In3.Cu" signal "GND1")
		(10 "In4.Cu" signal "IN2")
		(12 "In5.Cu" signal "VCC")
		(14 "In6.Cu" signal "VCC1")
		(16 "In7.Cu" signal "IN3")
		(18 "In8.Cu" signal "GND2")
		(20 "In9.Cu" signal "IN4")
		(22 "In10.Cu" signal "GND3")
		(2 "B.Cu" signal "BOTTOM")
		(9 "F.Adhes" user "F.Adhesive")
		(11 "B.Adhes" user "B.Adhesive")
		(13 "F.Paste" user "Package Geometry/Pastemask Top")
		(15 "B.Paste" user "Package Geometry/Pastemask Bottom")
		(5 "F.SilkS" user "Ref Des/Silkscreen Top")
		(7 "B.SilkS" user "Ref Des/Silkscreen Bottom")
		(1 "F.Mask" user "Board Geometry/Soldermask Top")
		(3 "B.Mask" user "Board Geometry/Soldermask Bottom")
		(17 "Dwgs.User" user "User.Drawings")
		(19 "Cmts.User" user "User.Comments")
		(21 "Eco1.User" user "User.Eco1")
		(23 "Eco2.User" user "User.Eco2")
		(25 "Edge.Cuts" user "Board Geometry/Outline")
		(27 "Margin" user)
		(31 "F.CrtYd" user "Package Geometry/Place Bound Top")
		(29 "B.CrtYd" user "Package Geometry/Place Bound Bottom")
		(35 "F.Fab" user "Ref Des/Assembly Top")
		(33 "B.Fab" user "Ref Des/Assembly Bottom")
	)
	(footprint ""
		(layer "F.Cu")
		(at 21.459444 -93.587062 180)
		(property "Reference" "U25"
			(at -10.595356 -8.218932 0)
			(unlocked yes)
			(layer "F.SilkS")
			(effects
				(font
					(size 0.7874 0.5842)
					(thickness 0.1524)
				)
				(justify left)
			)
		)
		(property "Value" ""
			(at 0 0 180)
			(layer "F.Fab")
			(effects
				(font
					(size 1.27 1.27)
				)
			)
		)
		(duplicate_pad_numbers_are_jumpers no)
		(pad "F13" smd circle
			(at 3.599942 -1.999996 180)
			(size 0.4064 0.4064)
			(layers "F.Cu" "F.Mask" "F.Paste")
			(net "SMB_BMC_ALERT9_R1_N")
		)
		(pad "F14" smd circle
			(at 4.400042 -1.999996 180)
			(size 0.4064 0.4064)
			(layers "F.Cu" "F.Mask" "F.Paste")
			(net "BMC_CPLD_GPIO_8_R2")
		)
		(pad "F15" smd circle
			(at 5.199888 -1.999996 180)
			(size 0.4064 0.4064)
			(layers "F.Cu" "F.Mask" "F.Paste")
			(net "BMC_CPLD_GPIO_7_R2")
		)
		(pad "F16" smd circle
			(at 5.999988 -1.999996 180)
			(size 0.4064 0.4064)
			(layers "F.Cu" "F.Mask" "F.Paste")
			(net "Net_77")
		)
		(pad "G1" smd circle
			(at -5.999988 -1.199896 180)
			(size 0.4064 0.4064)
			(layers "F.Cu" "F.Mask" "F.Paste")
			(net "Net_284")
		)
		(pad "G2" smd circle
			(at -5.199888 -1.199896 180)
			(size 0.4064 0.4064)
			(layers "F.Cu" "F.Mask" "F.Paste")
			(net "Net_312")
		)
		(pad "G3" smd circle
			(at -4.400042 -1.199896 180)
			(size 0.4064 0.4064)
			(layers "F.Cu" "F.Mask" "F.Paste")
			(net "Net_313")
		)
		(pad "G4" smd circle
			(at -3.599942 -1.199896 180)
			(size 0.4064 0.4064)
			(layers "F.Cu" "F.Mask" "F.Paste")
			(net "Net_311")
		)
		(pad "G5" smd circle
			(at -2.800096 -1.199896 180)
			(size 0.4064 0.4064)
			(layers "F.Cu" "F.Mask" "F.Paste")
			(net "Net_310")
		)
		(pad "G6" smd circle
			(at -1.999996 -1.199896 180)
			(size 0.4064 0.4064)
			(layers "F.Cu" "F.Mask" "F.Paste")
			(net "Net_307")
		)
		(pad "G7" smd circle
			(at -1.199896 -1.199896 180)
			(size 0.4064 0.4064)
			(layers "F.Cu" "F.Mask" "F.Paste")
			(net "PVCCA_AUX_PLD")
		)
		(pad "G8" smd circle
			(at -0.40005 -1.199896 180)
			(size 0.4064 0.4064)
			(layers "F.Cu" "F.Mask" "F.Paste")
			(net "VCCIO0")
		)
		(pad "G9" smd circle
			(at 0.40005 -1.199896 180)
			(size 0.4064 0.4064)
			(layers "F.Cu" "F.Mask" "F.Paste")
			(net "VCCIO0")
		)
		(pad "G10" smd circle
			(at 1.199896 -1.199896 180)
			(size 0.4064 0.4064)
			(layers "F.Cu" "F.Mask" "F.Paste")
			(net "PVCCA_AUX_PLD")
		)
		(pad "G11" smd circle
			(at 1.999996 -1.199896 180)
			(size 0.4064 0.4064)
			(layers "F.Cu" "F.Mask" "F.Paste")
			(net "FM_SLPS3_GF_R_N")
		)
		(pad "G12" smd circle
			(at 2.800096 -1.199896 180)
			(size 0.4064 0.4064)
			(layers "F.Cu" "F.Mask" "F.Paste")
			(net "SMB_BMC_ALERT10_R1_N")
		)
		(pad "G13" smd circle
			(at 3.599942 -1.199896 180)
			(size 0.4064 0.4064)
			(layers "F.Cu" "F.Mask" "F.Paste")
			(net "RST_BMC_SELF_HW_R2")
		)
		(pad "G14" smd circle
			(at 4.400042 -1.199896 180)
			(size 0.4064 0.4064)
			(layers "F.Cu" "F.Mask" "F.Paste")
			(net "Net_70")
		)
		(pad "G15" smd circle
			(at 5.199888 -1.199896 180)
			(size 0.4064 0.4064)
			(layers "F.Cu" "F.Mask" "F.Paste")
			(net "Net_69")
		)
		(pad "G16" smd circle
			(at 5.999988 -1.199896 180)
			(size 0.4064 0.4064)
			(layers "F.Cu" "F.Mask" "F.Paste")
			(net "BMC_CPLD_GPIO_12_R2")
		)
		(pad "H1" smd circle
			(at -5.999988 -0.40005 180)
			(size 0.4064 0.4064)
			(layers "F.Cu" "F.Mask" "F.Paste")
			(net "Net_289")
		)
		(pad "H2" smd circle
			(at -5.199888 -0.40005 180)
			(size 0.4064 0.4064)
			(layers "F.Cu" "F.Mask" "F.Paste")
			(net "Net_285")
		)
		(pad "H3" smd circle
			(at -4.400042 -0.40005 180)
			(size 0.4064 0.4064)
			(layers "F.Cu" "F.Mask" "F.Paste")
			(net "Net_288")
		)
		(pad "H4" smd circle
			(at -3.599942 -0.40005 180)
			(size 0.4064 0.4064)
			(layers "F.Cu" "F.Mask" "F.Paste")
			(net "Net_286")
		)
		(pad "H5" smd circle
			(at -2.800096 -0.40005 180)
			(size 0.4064 0.4064)
			(layers "F.Cu" "F.Mask" "F.Paste")
			(net "Net_294")
		)
		(pad "H6" smd circle
			(at -1.999996 -0.40005 180)
			(size 0.4064 0.4064)
			(layers "F.Cu" "F.Mask" "F.Paste")
			(net "Net_315")
		)
		(pad "H7" smd circle
			(at -1.199896 -0.40005 180)
			(size 0.4064 0.4064)
			(layers "F.Cu" "F.Mask" "F.Paste")
			(net "VCCIO4")
		)
		(pad "H8" smd circle
			(at -0.40005 -0.40005 180)
			(size 0.4064 0.4064)
			(layers "F.Cu" "F.Mask" "F.Paste")
			(net "GND")
		)
		(pad "H9" smd circle
			(at 0.40005 -0.40005 180)
			(size 0.4064 0.4064)
			(layers "F.Cu" "F.Mask" "F.Paste")
			(net "GND")
		)
		(pad "H10" smd circle
			(at 1.199896 -0.40005 180)
			(size 0.4064 0.4064)
			(layers "F.Cu" "F.Mask" "F.Paste")
			(net "VCCIO1")
		)
		(pad "H11" smd circle
			(at 1.999996 -0.40005 180)
			(size 0.4064 0.4064)
			(layers "F.Cu" "F.Mask" "F.Paste")
			(net "RST_MB_STBY_R_N")
		)
		(pad "H12" smd circle
			(at 2.800096 -0.40005 180)
			(size 0.4064 0.4064)
			(layers "F.Cu" "F.Mask" "F.Paste")
			(net "RST_ROT_CPU_R_N")
		)
		(pad "H13" smd circle
			(at 3.599942 -0.40005 180)
			(size 0.4064 0.4064)
			(layers "F.Cu" "F.Mask" "F.Paste")
			(net "FM_ESPI_PLD_R_EN")
		)
		(pad "H14" smd circle
			(at 4.400042 -0.40005 180)
			(size 0.4064 0.4064)
			(layers "F.Cu" "F.Mask" "F.Paste")
			(net "Net_71")
		)
		(pad "H15" smd circle
			(at 5.199888 -0.40005 180)
			(size 0.4064 0.4064)
			(layers "F.Cu" "F.Mask" "F.Paste")
			(net "BMC_CPLD_GPIO_13_R2")
		)
		(pad "H16" smd circle
			(at 5.999988 -0.40005 180)
			(size 0.4064 0.4064)
			(layers "F.Cu" "F.Mask" "F.Paste")
			(net "Net_72")
		)
		(pad "J1" smd circle
			(at -5.999988 0.40005 180)
			(size 0.4064 0.4064)
			(layers "F.Cu" "F.Mask" "F.Paste")
			(net "Net_290")
		)
		(pad "J2" smd circle
			(at -5.199888 0.40005 180)
			(size 0.4064 0.4064)
			(layers "F.Cu" "F.Mask" "F.Paste")
			(net "Net_292")
		)
		(pad "J3" smd circle
			(at -4.400042 0.40005 180)
			(size 0.4064 0.4064)
			(layers "F.Cu" "F.Mask" "F.Paste")
			(net "Net_291")
		)
		(pad "J4" smd circle
			(at -3.599942 0.40005 180)
			(size 0.4064 0.4064)
			(layers "F.Cu" "F.Mask" "F.Paste")
			(net "Net_295")
		)
		(pad "J5" smd circle
			(at -2.800096 0.40005 180)
			(size 0.4064 0.4064)
			(layers "F.Cu" "F.Mask" "F.Paste")
			(net "Net_282")
		)
		(pad "J6" smd circle
			(at -1.999996 0.40005 180)
			(size 0.4064 0.4064)
			(layers "F.Cu" "F.Mask" "F.Paste")
			(net "Net_287")
		)
		(pad "J7" smd circle
			(at -1.199896 0.40005 180)
			(size 0.4064 0.4064)
			(layers "F.Cu" "F.Mask" "F.Paste")
			(net "VCCIO4")
		)
		(pad "J8" smd circle
			(at -0.40005 0.40005 180)
			(size 0.4064 0.4064)
			(layers "F.Cu" "F.Mask" "F.Paste")
			(net "GND")
		)
		(pad "J9" smd circle
			(at 0.40005 0.40005 180)
			(size 0.4064 0.4064)
			(layers "F.Cu" "F.Mask" "F.Paste")
			(net "GND")
		)
		(pad "J10" smd circle
			(at 1.199896 0.40005 180)
			(size 0.4064 0.4064)
			(layers "F.Cu" "F.Mask" "F.Paste")
			(net "VCCIO1")
		)
		(pad "J11" smd circle
			(at 1.999996 0.40005 180)
			(size 0.4064 0.4064)
			(layers "F.Cu" "F.Mask" "F.Paste")
			(net "Net_37")
		)
		(pad "J12" smd circle
			(at 2.800096 0.40005 180)
			(size 0.4064 0.4064)
			(layers "F.Cu" "F.Mask" "F.Paste")
			(net "FM_THROTTLE_R_N")
		)
	)
)
